# TIMECARD (Time Appliance Project (Time Card)) — schematic netlist excerpt (pin names and nets, part order shuffled) for the footprints in the layout excerpt that follows; sources: Cadence DE-HDL packaged netlist, KiCad conversion of R4006-B0001-02_R01.brd

C206  CAPACITOR  0.1UF 10V 10%  pkg SMC_0402R_H022  page 14 : \1\ = XP1R8V_FPGA_VCCAUX ; \2\ = SG
R80  RESISTOR  33OHM 1%  pkg SMC_0402R_H016  page 20 : \1\ = FPGA_OUT_BNO080_BOOT_N ; \2\ = R_BNO080_BOOT_N

(kicad_pcb
	(version 20260206)
	(generator "pcbnew")
	(generator_version "10.0")
	(general
		(thickness 1.6)
		(legacy_teardrops no)
	)
	(paper "A4")
	(title_block
		(title "timecard-production-celestica-r4006 — R4006-B0001-02_R01.brd")
		(comment 1 "Time Appliance Project (Time Card) / footprints 999-1000 of 1113")
	)
	(layers
		(0 "F.Cu" signal "TOP")
		(4 "In1.Cu" signal "L02_GND1")
		(6 "In2.Cu" signal "L03_SIG1")
		(8 "In3.Cu" signal "L04_GND2")
		(10 "In4.Cu" signal "L05_VCC1")
		(12 "In5.Cu" signal "L06_VCC2")
		(14 "In6.Cu" signal "L07_GND3")
		(16 "In7.Cu" signal "L08_SIG2")
		(18 "In8.Cu" signal "L09_GND4")
		(2 "B.Cu" signal "BOTTOM")
		(9 "F.Adhes" user "F.Adhesive")
		(11 "B.Adhes" user "B.Adhesive")
		(13 "F.Paste" user "Package Geometry/Pastemask Top")
		(15 "B.Paste" user "Package Geometry/Pastemask Bottom")
		(5 "F.SilkS" user "Ref Des/Silkscreen Top")
		(7 "B.SilkS" user "Ref Des/Silkscreen Bottom")
		(1 "F.Mask" user "Board Geometry/Soldermask Top")
		(3 "B.Mask" user "Board Geometry/Soldermask Bottom")
		(17 "Dwgs.User" user "User.Drawings")
		(19 "Cmts.User" user "User.Comments")
		(21 "Eco1.User" user "User.Eco1")
		(23 "Eco2.User" user "User.Eco2")
		(25 "Edge.Cuts" user "Board Geometry/Outline")
		(27 "Margin" user)
		(31 "F.CrtYd" user "Package Geometry/Place Bound Top")
		(29 "B.CrtYd" user "Package Geometry/Place Bound Bottom")
		(35 "F.Fab" user "Ref Des/Assembly Top")
		(33 "B.Fab" user "Ref Des/Assembly Bottom")
	)
	(footprint ""
		(layer "B.Cu")
		(at 84.709 -64.3128 90)
		(property "Reference" "R80"
			(at -0.3048 1.10363 270)
			(unlocked yes)
			(layer "B.SilkS")
			(effects
				(font
					(size 0.7874 0.5842)
					(thickness 0.1524)
				)
				(justify mirror)
			)
		)
		(property "Value" "VAL*"
			(at -0.02032 2.13233 90)
			(unlocked yes)
			(layer "B.Fab")
			(hide yes)
			(effects
				(font
					(size 0.7874 0.5842)
					(thickness 0.1524)
				)
				(justify mirror)
			)
		)
		(property "Device Type" "RESISTOR-G155-133R0-01,33OHM,1%"
			(at -0.008382 1.210564 90)
			(unlocked yes)
			(layer "B.Fab")
			(hide yes)
			(effects
				(font
					(size 0.7874 0.5842)
					(thickness 0.1524)
				)
				(justify mirror)
			)
		)
		(property "User Part Number" "PARTNUM*"
			(at -0.02032 4.024884 90)
			(unlocked yes)
			(layer "Cmts.User")
			(hide yes)
			(effects
				(font
					(size 0.7874 0.5842)
					(thickness 0.1524)
				)
				(justify mirror)
			)
		)
		(property "Tolerance" "TOL*"
			(at -0.044704 3.05435 90)
			(unlocked yes)
			(layer "Cmts.User")
			(hide yes)
			(effects
				(font
					(size 0.7874 0.5842)
					(thickness 0.1524)
				)
				(justify mirror)
			)
		)
		(duplicate_pad_numbers_are_jumpers no)
		(fp_line
			(start 1.143 -0.5588)
			(end 1.143 0.5588)
			(stroke
				(width 0.1)
				(type default)
			)
			(layer "B.SilkS")
		)
		(fp_line
			(start -1.143 -0.5588)
			(end 1.143 -0.5588)
			(stroke
				(width 0.1)
				(type default)
			)
			(layer "B.SilkS")
		)
		(fp_line
			(start 1.143 0.5588)
			(end -1.143 0.5588)
			(stroke
				(width 0.1)
				(type default)
			)
			(layer "B.SilkS")
		)
		(fp_line
			(start -1.143 0.5588)
			(end -1.143 -0.5588)
			(stroke
				(width 0.1)
				(type default)
			)
			(layer "B.SilkS")
		)
		(fp_rect
			(start -1.143 -0.5588)
			(end 1.143 0.5588)
			(stroke
				(width 0)
				(type default)
			)
			(fill no)
			(layer "B.CrtYd")
		)
		(fp_line
			(start 0.508 -0.3048)
			(end 0.508 0.3048)
			(stroke
				(width 0.1)
				(type default)
			)
			(layer "B.Fab")
		)
		(fp_line
			(start -0.508 -0.3048)
			(end 0.508 -0.3048)
			(stroke
				(width 0.1)
				(type default)
			)
			(layer "B.Fab")
		)
		(fp_line
			(start 0.508 0.3048)
			(end -0.508 0.3048)
			(stroke
				(width 0.1)
				(type default)
			)
			(layer "B.Fab")
		)
		(fp_line
			(start -0.508 0.3048)
			(end -0.508 -0.3048)
			(stroke
				(width 0.1)
				(type default)
			)
			(layer "B.Fab")
		)
		(pad "1" smd rect
			(at 0.5334 0 270)
			(size 0.7112 0.6096)
			(layers "B.Cu" "B.Mask" "B.Paste")
			(net "FPGA_OUT_BNO080_BOOT_N")
		)
		(pad "2" smd rect
			(at -0.5334 0 270)
			(size 0.7112 0.6096)
			(layers "B.Cu" "B.Mask" "B.Paste")
			(net "R_BNO080_BOOT_N")
		)
		(zone
			(layer "B.Cu")
			(hatch none 0.5)
			(connect_pads
				(clearance 0)
			)
			(min_thickness 0.25)
			(keepout
				(tracks allowed)
				(vias not_allowed)
				(pads allowed)
				(copperpour not_allowed)
				(footprints allowed)
			)
			(placement
				(enabled no)
				(sheetname "")
			)
			(fill
				(thermal_gap 0.5)
				(thermal_bridge_width 0.5)
				(island_removal_mode 0)
			)
			(polygon
				(pts
					(xy 84.4042 -64.2366) (xy 85.0138 -64.2366) (xy 85.0138 -64.389) (xy 84.4042 -64.389)
				)
			)
		)
	)
	(footprint ""
		(layer "B.Cu")
		(at 111.34725 -45.823124 180)
		(property "Reference" "C206"
			(at 43.14825 -1.023874 0)
			(unlocked yes)
			(layer "B.SilkS")
			(effects
				(font
					(size 0.635 0.4064)
					(thickness 0.1524)
				)
				(justify mirror)
			)
		)
		(property "Value" "VAL*"
			(at 0 3.718306 180)
			(unlocked yes)
			(layer "B.Fab")
			(hide yes)
			(effects
				(font
					(size 0.7874 0.5842)
					(thickness 0.127)
				)
				(justify mirror)
			)
		)
		(property "Device Type" "CAPACITOR-G105-0B104-CK,0.1UF,A"
			(at 0 1.432306 180)
			(unlocked yes)
			(layer "B.Fab")
			(hide yes)
			(effects
				(font
					(size 0.7874 0.5842)
					(thickness 0.127)
				)
				(justify mirror)
			)
		)
		(property "User Part Number" "PARTNUM*"
			(at 0 2.575306 180)
			(unlocked yes)
			(layer "Cmts.User")
			(hide yes)
			(effects
				(font
					(size 0.7874 0.5842)
					(thickness 0.127)
				)
				(justify mirror)
			)
		)
		(property "Tolerance" "TOL*"
			(at 0 4.861306 180)
			(unlocked yes)
			(layer "Cmts.User")
			(hide yes)
			(effects
				(font
					(size 0.7874 0.5842)
					(thickness 0.127)
				)
				(justify mirror)
			)
		)
		(duplicate_pad_numbers_are_jumpers no)
		(fp_line
			(start 0.970026 0.4699)
			(end 0.970026 -0.4699)
			(stroke
				(width 0.1)
				(type default)
			)
			(layer "B.SilkS")
		)
		(fp_line
			(start 0.970026 -0.4699)
			(end -0.970026 -0.4699)
			(stroke
				(width 0.1)
				(type default)
			)
			(layer "B.SilkS")
		)
		(fp_line
			(start -0.970026 0.4699)
			(end 0.970026 0.4699)
			(stroke
				(width 0.1)
				(type default)
			)
			(layer "B.SilkS")
		)
		(fp_line
			(start -0.970026 -0.4699)
			(end -0.970026 0.4699)
			(stroke
				(width 0.1)
				(type default)
			)
			(layer "B.SilkS")
		)
		(fp_poly
			(pts
				(xy 0.970026 0.4699) (xy -0.970026 0.4699) (xy -0.970026 -0.4699) (xy 0.970026 -0.4699)
			)
			(stroke
				(width 0)
				(type default)
			)
			(fill no)
			(layer "B.CrtYd")
		)
		(fp_line
			(start 0.508 0.3048)
			(end 0.508 -0.3048)
			(stroke
				(width 0.1)
				(type default)
			)
			(layer "B.Fab")
		)
		(fp_line
			(start 0.508 -0.3048)
			(end -0.508 -0.3048)
			(stroke
				(width 0.1)
				(type default)
			)
			(layer "B.Fab")
		)
		(fp_line
			(start -0.508 0.3048)
			(end 0.508 0.3048)
			(stroke
				(width 0.1)
				(type default)
			)
			(layer "B.Fab")
		)
		(fp_line
			(start -0.508 -0.3048)
			(end -0.508 0.3048)
			(stroke
				(width 0.1)
				(type default)
			)
			(layer "B.Fab")
		)
		(pad "1" smd circle
			(at 0.500126 0)
			(size 0.635 0.635)
			(layers "B.Cu" "B.Mask" "B.Paste")
			(net "XP1R8V_FPGA_VCCAUX")
		)
		(pad "2" smd circle
			(at -0.500126 0)
			(size 0.635 0.635)
			(layers "B.Cu" "B.Mask" "B.Paste")
			(net "SG")
		)
	)
)
